# BASEBOARD_FAB2 (Tioga Pass) — schematic netlist excerpt (pin names and nets, part order shuffled) for the footprints in the layout excerpt that follows; sources: Cadence DE-HDL packaged netlist, KiCad conversion of Wiwynn_Tioga_Pass_MB.brd

R4D66  RES  0.0 5% CHIP  pkg 0402  page 201 : A = SVID_VDIO_PVCCIN_CPU0 ; B = SVID_DIO0_CPU0_R
R25W3  120R2F-GP  1%  pkg RCL_GP  page 151 : \1\ = GND ; \2\ = BMC_M_RST_N
R1C33  RES  1.00K 1% CHIP  pkg 0402  page 156 : A = GND ; B = PD_PIROM_CPU1_ADDR1

(kicad_pcb
	(version 20260206)
	(generator "pcbnew")
	(generator_version "10.0")
	(general
		(thickness 1.6)
		(legacy_teardrops no)
	)
	(paper "A4")
	(title_block
		(title "Wiwynn_Tioga_Pass_MB.brd")
		(comment 1 "Tioga Pass / footprints 629-631 of 4770")
	)
	(layers
		(0 "F.Cu" signal "TOP")
		(4 "In1.Cu" signal "L2GND")
		(6 "In2.Cu" signal "L3")
		(8 "In3.Cu" signal "L4GND")
		(10 "In4.Cu" signal "L5")
		(12 "In5.Cu" signal "L6GND")
		(14 "In6.Cu" signal "L7VCC")
		(16 "In7.Cu" signal "L8VCC")
		(18 "In8.Cu" signal "L9GND")
		(20 "In9.Cu" signal "L10")
		(22 "In10.Cu" signal "L11GND")
		(24 "In11.Cu" signal "L12")
		(26 "In12.Cu" signal "L13GND")
		(2 "B.Cu" signal "BOTTOM")
		(9 "F.Adhes" user "F.Adhesive")
		(11 "B.Adhes" user "B.Adhesive")
		(13 "F.Paste" user "Package Geometry/Pastemask Top")
		(15 "B.Paste" user "Package Geometry/Pastemask Bottom")
		(5 "F.SilkS" user "Ref Des/Silkscreen Top")
		(7 "B.SilkS" user "Ref Des/Silkscreen Bottom")
		(1 "F.Mask" user "Board Geometry/Soldermask Top")
		(3 "B.Mask" user "Board Geometry/Soldermask Bottom")
		(17 "Dwgs.User" user "User.Drawings")
		(19 "Cmts.User" user "User.Comments")
		(21 "Eco1.User" user "User.Eco1")
		(23 "Eco2.User" user "User.Eco2")
		(25 "Edge.Cuts" user "Board Geometry/Outline")
		(27 "Margin" user)
		(31 "F.CrtYd" user "Package Geometry/Place Bound Top")
		(29 "B.CrtYd" user "Package Geometry/Place Bound Bottom")
		(35 "F.Fab" user "Ref Des/Assembly Top")
		(33 "B.Fab" user "Ref Des/Assembly Bottom")
	)
	(footprint ""
		(layer "F.Cu")
		(at 183.769 -65.024)
		(property "Reference" "R4D66"
			(at 0 0 0)
			(layer "F.SilkS")
			(hide yes)
			(effects
				(font
					(size 1.27 1.27)
				)
			)
		)
		(property "Value" ""
			(at 0 0 0)
			(layer "F.Fab")
			(effects
				(font
					(size 1.27 1.27)
				)
			)
		)
		(duplicate_pad_numbers_are_jumpers no)
		(fp_rect
			(start -0.2794 0.9906)
			(end 0.2794 -0.1016)
			(stroke
				(width 0)
				(type default)
			)
			(fill no)
			(layer "F.CrtYd")
		)
		(fp_line
			(start -0.2794 -0.1016)
			(end -0.2794 0.9906)
			(stroke
				(width 0.1)
				(type default)
			)
			(layer "F.Fab")
		)
		(fp_line
			(start -0.2794 0.9906)
			(end 0.2794 0.9906)
			(stroke
				(width 0.1)
				(type default)
			)
			(layer "F.Fab")
		)
		(fp_line
			(start 0.2794 -0.1016)
			(end -0.2794 -0.1016)
			(stroke
				(width 0.1)
				(type default)
			)
			(layer "F.Fab")
		)
		(fp_line
			(start 0.2794 0.9906)
			(end 0.2794 -0.1016)
			(stroke
				(width 0.1)
				(type default)
			)
			(layer "F.Fab")
		)
		(pad "1" smd rect
			(at 0 0)
			(size 0.508 0.508)
			(layers "F.Cu" "F.Mask" "F.Paste")
			(net "SVID_VDIO_PVCCIN_CPU0")
		)
		(pad "2" smd rect
			(at 0 0.889)
			(size 0.508 0.508)
			(layers "F.Cu" "F.Mask" "F.Paste")
			(net "SVID_DIO0_CPU0_R")
		)
		(zone
			(layer "F.Cu")
			(hatch none 0.5)
			(connect_pads
				(clearance 0)
			)
			(min_thickness 0.25)
			(keepout
				(tracks allowed)
				(vias not_allowed)
				(pads allowed)
				(copperpour not_allowed)
				(footprints allowed)
			)
			(placement
				(enabled no)
				(sheetname "")
			)
			(fill
				(thermal_gap 0.5)
				(thermal_bridge_width 0.5)
				(island_removal_mode 0)
			)
			(polygon
				(pts
					(xy 183.515 -64.389) (xy 184.023 -64.389) (xy 184.023 -64.77) (xy 183.515 -64.77)
				)
			)
		)
		(zone
			(layer "F.Cu")
			(hatch none 0.5)
			(connect_pads
				(clearance 0)
			)
			(min_thickness 0.25)
			(keepout
				(tracks not_allowed)
				(vias allowed)
				(pads allowed)
				(copperpour not_allowed)
				(footprints allowed)
			)
			(placement
				(enabled no)
				(sheetname "")
			)
			(fill
				(thermal_gap 0.5)
				(thermal_bridge_width 0.5)
				(island_removal_mode 0)
			)
			(polygon
				(pts
					(xy 183.515 -64.389) (xy 184.023 -64.389) (xy 184.023 -64.77) (xy 183.515 -64.77)
				)
			)
		)
	)
	(footprint ""
		(layer "F.Cu")
		(at 449.69938 -35.8775 90)
		(property "Reference" "R25W3"
			(at 0 0 90)
			(layer "F.SilkS")
			(hide yes)
			(effects
				(font
					(size 1.27 1.27)
				)
			)
		)
		(property "Value" "*"
			(at 0.064008 -4.108196 90)
			(unlocked yes)
			(layer "F.Fab")
			(hide yes)
			(effects
				(font
					(size 1.27 1.016)
					(thickness 0.1524)
				)
			)
		)
		(property "Device Type" "120R2F-GP_RCL_GP-120R2F-GP,64.A"
			(at 0.064008 -5.632196 90)
			(unlocked yes)
			(layer "F.Fab")
			(hide yes)
			(effects
				(font
					(size 1.27 1.016)
					(thickness 0.1524)
				)
			)
		)
		(duplicate_pad_numbers_are_jumpers no)
		(fp_line
			(start 0.508 -0.9398)
			(end -0.508 -0.9398)
			(stroke
				(width 0.1524)
				(type default)
			)
			(layer "F.SilkS")
		)
		(fp_line
			(start -0.508 -0.9398)
			(end -0.508 0.9398)
			(stroke
				(width 0.1524)
				(type default)
			)
			(layer "F.SilkS")
		)
		(fp_rect
			(start -0.508 0.9398)
			(end 0.508 -0.9398)
			(stroke
				(width 0)
				(type default)
			)
			(fill no)
			(layer "F.CrtYd")
		)
		(fp_rect
			(start -0.508 0.9398)
			(end 0.508 -0.9398)
			(stroke
				(width 0)
				(type default)
			)
			(fill no)
			(layer "F.Fab")
		)
		(pad "1" smd custom
			(at 0 -0.4445 90)
			(size 0.1397 0.1397)
			(layers "F.Cu" "F.Mask" "F.Paste")
			(net "GND")
			(options
				(clearance outline)
				(anchor circle)
			)
			(primitives
				(gr_poly
					(pts
						(arc
							(start -0.1778 -0.2794)
							(mid -0.249642 -0.249642)
							(end -0.2794 -0.1778)
						)
						(arc
							(start -0.2794 0.1778)
							(mid -0.249642 0.249642)
							(end -0.1778 0.2794)
						)
						(arc
							(start 0.1778 0.2794)
							(mid 0.249642 0.249642)
							(end 0.2794 0.1778)
						)
						(arc
							(start 0.2794 -0.1778)
							(mid 0.249642 -0.249642)
							(end 0.1778 -0.2794)
						)
					)
					(width 0)
					(fill yes)
				)
			)
		)
		(pad "2" smd custom
			(at 0 0.4445 90)
			(size 0.1397 0.1397)
			(layers "F.Cu" "F.Mask" "F.Paste")
			(net "BMC_M_RST_N")
			(options
				(clearance outline)
				(anchor circle)
			)
			(primitives
				(gr_poly
					(pts
						(arc
							(start -0.1778 -0.2794)
							(mid -0.249642 -0.249642)
							(end -0.2794 -0.1778)
						)
						(arc
							(start -0.2794 0.1778)
							(mid -0.249642 0.249642)
							(end -0.1778 0.2794)
						)
						(arc
							(start 0.1778 0.2794)
							(mid 0.249642 0.249642)
							(end 0.2794 0.1778)
						)
						(arc
							(start 0.2794 -0.1778)
							(mid 0.249642 -0.249642)
							(end 0.1778 -0.2794)
						)
					)
					(width 0)
					(fill yes)
				)
			)
		)
	)
	(footprint ""
		(layer "F.Cu")
		(at 28.7274 -104.5718 90)
		(property "Reference" "R1C33"
			(at 0 0 90)
			(layer "F.SilkS")
			(hide yes)
			(effects
				(font
					(size 1.27 1.27)
				)
			)
		)
		(property "Value" ""
			(at 0 0 90)
			(layer "F.Fab")
			(effects
				(font
					(size 1.27 1.27)
				)
			)
		)
		(duplicate_pad_numbers_are_jumpers no)
		(fp_poly
			(pts
				(xy -0.2794 -0.1016) (xy 0.2794 -0.1016) (xy 0.2794 0.9906) (xy -0.2794 0.9906)
			)
			(stroke
				(width 0)
				(type default)
			)
			(fill no)
			(layer "F.CrtYd")
		)
		(fp_line
			(start 0.2794 -0.1016)
			(end -0.2794 -0.1016)
			(stroke
				(width 0.1)
				(type default)
			)
			(layer "F.Fab")
		)
		(fp_line
			(start -0.2794 -0.1016)
			(end -0.2794 0.9906)
			(stroke
				(width 0.1)
				(type default)
			)
			(layer "F.Fab")
		)
		(fp_line
			(start 0.2794 0.9906)
			(end 0.2794 -0.1016)
			(stroke
				(width 0.1)
				(type default)
			)
			(layer "F.Fab")
		)
		(fp_line
			(start -0.2794 0.9906)
			(end 0.2794 0.9906)
			(stroke
				(width 0.1)
				(type default)
			)
			(layer "F.Fab")
		)
		(pad "1" smd rect
			(at 0 0 90)
			(size 0.508 0.508)
			(layers "F.Cu" "F.Mask" "F.Paste")
			(net "GND")
		)
		(pad "2" smd rect
			(at 0 0.889 90)
			(size 0.508 0.508)
			(layers "F.Cu" "F.Mask" "F.Paste")
			(net "PD_PIROM_CPU1_ADDR1")
		)
		(zone
			(layer "F.Cu")
			(hatch none 0.5)
			(connect_pads
				(clearance 0)
			)
			(min_thickness 0.25)
			(keepout
				(tracks allowed)
				(vias not_allowed)
				(pads allowed)
				(copperpour not_allowed)
				(footprints allowed)
			)
			(placement
				(enabled no)
				(sheetname "")
			)
			(fill
				(thermal_gap 0.5)
				(thermal_bridge_width 0.5)
				(island_removal_mode 0)
			)
			(polygon
				(pts
					(xy 28.9814 -104.3178) (xy 28.9814 -104.8258) (xy 29.3624 -104.8258) (xy 29.3624 -104.3178)
				)
			)
		)
		(zone
			(layer "F.Cu")
			(hatch none 0.5)
			(connect_pads
				(clearance 0)
			)
			(min_thickness 0.25)
			(keepout
				(tracks not_allowed)
				(vias allowed)
				(pads allowed)
				(copperpour not_allowed)
				(footprints allowed)
			)
			(placement
				(enabled no)
				(sheetname "")
			)
			(fill
				(thermal_gap 0.5)
				(thermal_bridge_width 0.5)
				(island_removal_mode 0)
			)
			(polygon
				(pts
					(xy 29.3624 -104.3178) (xy 29.3624 -104.8258) (xy 28.9814 -104.8258) (xy 28.9814 -104.3178)
				)
			)
		)
	)
)
